(kicad_pcb
	(version 20260206)
	(generator "pcbnew")
	(generator_version "10.0")
	(general
		(thickness 1.6)
		(legacy_teardrops no)
	)
	(paper "A4")
	(title_block
		(title "Bryce Canyon_F.DPB_16315-1-OCP.brd")
		(comment 1 "Bryce Canyon / footprints 1025-1029 of 2223")
	)
	(layers
		(0 "F.Cu" signal "TOP")
		(4 "In1.Cu" signal "L2GND")
		(6 "In2.Cu" signal "L3")
		(8 "In3.Cu" signal "L4GND")
		(10 "In4.Cu" signal "L5")
		(12 "In5.Cu" signal "L6VCC")
		(14 "In6.Cu" signal "L7VCC")
		(16 "In7.Cu" signal "L8")
		(18 "In8.Cu" signal "L9GND")
		(20 "In9.Cu" signal "L10")
		(22 "In10.Cu" signal "L11GND")
		(2 "B.Cu" signal "BOTTOM")
		(9 "F.Adhes" user "F.Adhesive")
		(11 "B.Adhes" user "B.Adhesive")
		(13 "F.Paste" user "Package Geometry/Pastemask Top")
		(15 "B.Paste" user "Package Geometry/Pastemask Bottom")
		(5 "F.SilkS" user "Ref Des/Silkscreen Top")
		(7 "B.SilkS" user "Ref Des/Silkscreen Bottom")
		(1 "F.Mask" user "Board Geometry/Soldermask Top")
		(3 "B.Mask" user "Board Geometry/Soldermask Bottom")
		(17 "Dwgs.User" user "User.Drawings")
		(19 "Cmts.User" user "User.Comments")
		(21 "Eco1.User" user "User.Eco1")
		(23 "Eco2.User" user "User.Eco2")
		(25 "Edge.Cuts" user "Board Geometry/Outline")
		(27 "Margin" user)
		(31 "F.CrtYd" user "Package Geometry/Place Bound Top")
		(29 "B.CrtYd" user "Package Geometry/Place Bound Bottom")
		(35 "F.Fab" user "Ref Des/Assembly Top")
		(33 "B.Fab" user "Ref Des/Assembly Bottom")
	)
	(footprint ""
		(layer "F.Cu")
		(at 447.167 -184.912 180)
		(property "Reference" "R640"
			(at 0 0 180)
			(layer "F.SilkS")
			(hide yes)
			(effects
				(font
					(size 1.27 1.27)
				)
			)
		)
		(property "Value" "220R3F-1-GP"
			(at -0.0254 -2.5146 180)
			(unlocked yes)
			(layer "F.Fab")
			(hide yes)
			(effects
				(font
					(size 1.016 1.016)
					(thickness 0.1524)
				)
			)
		)
		(property "Device Type" "R603H22"
			(at -0.0254 -4.0386 180)
			(unlocked yes)
			(layer "F.Fab")
			(hide yes)
			(effects
				(font
					(size 1.016 1.016)
					(thickness 0.1524)
				)
			)
		)
		(duplicate_pad_numbers_are_jumpers no)
		(fp_line
			(start 0.2032 0)
			(end 0.4826 0)
			(stroke
				(width 0.2032)
				(type default)
			)
			(layer "F.SilkS")
		)
		(fp_line
			(start -0.4826 0)
			(end -0.2032 0)
			(stroke
				(width 0.2032)
				(type default)
			)
			(layer "F.SilkS")
		)
		(fp_rect
			(start -0.5842 1.3335)
			(end 0.5842 -1.3335)
			(stroke
				(width 0)
				(type default)
			)
			(fill no)
			(layer "F.CrtYd")
		)
		(fp_rect
			(start -0.5842 1.3335)
			(end 0.5842 -1.3335)
			(stroke
				(width 0)
				(type default)
			)
			(fill no)
			(layer "F.Fab")
		)
		(pad "1" smd custom
			(at 0 -0.762 180)
			(size 0.2159 0.2159)
			(layers "F.Cu" "F.Mask" "F.Paste")
			(net "HDD_PRSNT_22")
			(options
				(clearance outline)
				(anchor circle)
			)
			(primitives
				(gr_poly
					(pts
						(arc
							(start -0.3302 -0.4318)
							(mid -0.402042 -0.402042)
							(end -0.4318 -0.3302)
						)
						(arc
							(start -0.4318 0.3302)
							(mid -0.402042 0.402042)
							(end -0.3302 0.4318)
						)
						(arc
							(start 0.3302 0.4318)
							(mid 0.402042 0.402042)
							(end 0.4318 0.3302)
						)
						(arc
							(start 0.4318 -0.3302)
							(mid 0.402042 -0.402042)
							(end 0.3302 -0.4318)
						)
					)
					(width 0)
					(fill yes)
				)
			)
		)
		(pad "2" smd custom
			(at 0 0.762 180)
			(size 0.2159 0.2159)
			(layers "F.Cu" "F.Mask" "F.Paste")
			(net "DRIVE_A_22_INS")
			(options
				(clearance outline)
				(anchor circle)
			)
			(primitives
				(gr_poly
					(pts
						(arc
							(start -0.3302 -0.4318)
							(mid -0.402042 -0.402042)
							(end -0.4318 -0.3302)
						)
						(arc
							(start -0.4318 0.3302)
							(mid -0.402042 0.402042)
							(end -0.3302 0.4318)
						)
						(arc
							(start 0.3302 0.4318)
							(mid 0.402042 0.402042)
							(end 0.4318 0.3302)
						)
						(arc
							(start 0.4318 -0.3302)
							(mid 0.402042 -0.402042)
							(end 0.3302 -0.4318)
						)
					)
					(width 0)
					(fill yes)
				)
			)
		)
	)
	(footprint ""
		(layer "F.Cu")
		(at 204.004418 -162.9918)
		(property "Reference" "TC15"
			(at 0 0 0)
			(layer "F.SilkS")
			(hide yes)
			(effects
				(font
					(size 1.27 1.27)
				)
			)
		)
		(property "Value" "SE270U16VM-8-GP"
			(at -4.5974 -2.54 0)
			(unlocked yes)
			(layer "F.Fab")
			(hide yes)
			(effects
				(font
					(size 1.016 1.016)
					(thickness 0.1524)
				)
			)
		)
		(property "Device Type" "SE361416H394"
			(at -4.5974 -4.064 0)
			(unlocked yes)
			(layer "F.Fab")
			(hide yes)
			(effects
				(font
					(size 1.016 1.016)
					(thickness 0.1524)
				)
			)
		)
		(duplicate_pad_numbers_are_jumpers no)
		(fp_line
			(start -3.556 -3.4163)
			(end -2.3622 -4.6101)
			(stroke
				(width 0.1524)
				(type default)
			)
			(layer "F.SilkS")
		)
		(fp_line
			(start -3.556 4.6101)
			(end -3.556 -3.4163)
			(stroke
				(width 0.1524)
				(type default)
			)
			(layer "F.SilkS")
		)
		(fp_line
			(start -2.3622 -4.6101)
			(end 2.3622 -4.6101)
			(stroke
				(width 0.1524)
				(type default)
			)
			(layer "F.SilkS")
		)
		(fp_line
			(start 2.3622 -4.6101)
			(end 3.556 -3.4163)
			(stroke
				(width 0.1524)
				(type default)
			)
			(layer "F.SilkS")
		)
		(fp_line
			(start 3.556 -3.4163)
			(end 3.556 4.6101)
			(stroke
				(width 0.1524)
				(type default)
			)
			(layer "F.SilkS")
		)
		(fp_line
			(start 3.556 4.6101)
			(end -3.556 4.6101)
			(stroke
				(width 0.1524)
				(type default)
			)
			(layer "F.SilkS")
		)
		(fp_rect
			(start -3.302 3.6449)
			(end 3.302 -3.6449)
			(stroke
				(width 0)
				(type default)
			)
			(fill no)
			(layer "F.CrtYd")
		)
		(fp_poly
			(pts
				(xy 3.81 4.6863) (xy 3.81 -3.4925) (xy 3.302 -3.4925) (xy 3.302 3.6449) (xy -3.302 3.6449) (xy -3.302 -3.6449)
				(xy 3.302 -3.6449) (xy 3.302 -3.5052) (xy 3.81 -3.5052) (xy 3.81 -4.6863) (xy -3.81 -4.6863) (xy -3.81 4.6863)
			)
			(stroke
				(width 0)
				(type default)
			)
			(fill no)
			(layer "F.CrtYd")
		)
		(fp_rect
			(start -3.81 4.6863)
			(end 3.81 -4.6863)
			(stroke
				(width 0)
				(type default)
			)
			(fill no)
			(layer "F.Fab")
		)
		(pad "1" smd rect
			(at 0 -2.574036)
			(size 1.4224 3.556)
			(layers "F.Cu" "F.Mask" "F.Paste")
			(net "P12V_A")
		)
		(pad "2" smd rect
			(at 0 2.574036)
			(size 1.4224 3.556)
			(layers "F.Cu" "F.Mask" "F.Paste")
			(net "GND")
		)
	)
	(footprint ""
		(layer "F.Cu")
		(at 141.423898 -47.157894 180)
		(property "Reference" "R790"
			(at 0 0 180)
			(layer "F.SilkS")
			(hide yes)
			(effects
				(font
					(size 1.27 1.27)
				)
			)
		)
		(property "Value" "200KR2F-L-GP"
			(at 0.064008 -3.993896 180)
			(unlocked yes)
			(layer "F.Fab")
			(hide yes)
			(effects
				(font
					(size 1.016 1.016)
					(thickness 0.1524)
				)
			)
		)
		(property "Device Type" "R402H16"
			(at 0.064008 -5.517896 180)
			(unlocked yes)
			(layer "F.Fab")
			(hide yes)
			(effects
				(font
					(size 1.016 1.016)
					(thickness 0.1524)
				)
			)
		)
		(duplicate_pad_numbers_are_jumpers no)
		(fp_line
			(start 0.508 -0.9398)
			(end -0.508 -0.9398)
			(stroke
				(width 0.1524)
				(type default)
			)
			(layer "F.SilkS")
		)
		(fp_line
			(start -0.508 -0.9398)
			(end -0.508 0.9398)
			(stroke
				(width 0.1524)
				(type default)
			)
			(layer "F.SilkS")
		)
		(fp_rect
			(start -0.508 0.9398)
			(end 0.508 -0.9398)
			(stroke
				(width 0)
				(type default)
			)
			(fill no)
			(layer "F.CrtYd")
		)
		(fp_rect
			(start -0.508 0.9398)
			(end 0.508 -0.9398)
			(stroke
				(width 0)
				(type default)
			)
			(fill no)
			(layer "F.Fab")
		)
		(pad "1" smd custom
			(at 0 -0.4445 180)
			(size 0.1397 0.1397)
			(layers "F.Cu" "F.Mask" "F.Paste")
			(net "SW_HDD_R28")
			(options
				(clearance outline)
				(anchor circle)
			)
			(primitives
				(gr_poly
					(pts
						(arc
							(start -0.1778 -0.2794)
							(mid -0.249642 -0.249642)
							(end -0.2794 -0.1778)
						)
						(arc
							(start -0.2794 0.1778)
							(mid -0.249642 0.249642)
							(end -0.1778 0.2794)
						)
						(arc
							(start 0.1778 0.2794)
							(mid 0.249642 0.249642)
							(end 0.2794 0.1778)
						)
						(arc
							(start 0.2794 -0.1778)
							(mid 0.249642 -0.249642)
							(end 0.1778 -0.2794)
						)
					)
					(width 0)
					(fill yes)
				)
			)
		)
		(pad "2" smd custom
			(at 0 0.4445 180)
			(size 0.1397 0.1397)
			(layers "F.Cu" "F.Mask" "F.Paste")
			(net "SW_HDD_N28")
			(options
				(clearance outline)
				(anchor circle)
			)
			(primitives
				(gr_poly
					(pts
						(arc
							(start -0.1778 -0.2794)
							(mid -0.249642 -0.249642)
							(end -0.2794 -0.1778)
						)
						(arc
							(start -0.2794 0.1778)
							(mid -0.249642 0.249642)
							(end -0.1778 0.2794)
						)
						(arc
							(start 0.1778 0.2794)
							(mid 0.249642 0.249642)
							(end 0.2794 0.1778)
						)
						(arc
							(start 0.2794 -0.1778)
							(mid 0.249642 -0.249642)
							(end 0.1778 -0.2794)
						)
					)
					(width 0)
					(fill yes)
				)
			)
		)
	)
	(footprint ""
		(layer "F.Cu")
		(at 77.917548 -160.633918 90)
		(property "Reference" "R466"
			(at 0 0 90)
			(layer "F.SilkS")
			(hide yes)
			(effects
				(font
					(size 1.27 1.27)
				)
			)
		)
		(property "Value" "4K7R2J-2-GP"
			(at 0.064008 -3.993896 90)
			(unlocked yes)
			(layer "F.Fab")
			(hide yes)
			(effects
				(font
					(size 1.016 1.016)
					(thickness 0.1524)
				)
			)
		)
		(property "Device Type" "R402H16"
			(at 0.064008 -5.517896 90)
			(unlocked yes)
			(layer "F.Fab")
			(hide yes)
			(effects
				(font
					(size 1.016 1.016)
					(thickness 0.1524)
				)
			)
		)
		(duplicate_pad_numbers_are_jumpers no)
		(fp_line
			(start 0.508 -0.9398)
			(end -0.508 -0.9398)
			(stroke
				(width 0.1524)
				(type default)
			)
			(layer "F.SilkS")
		)
		(fp_line
			(start -0.508 -0.9398)
			(end -0.508 0.9398)
			(stroke
				(width 0.1524)
				(type default)
			)
			(layer "F.SilkS")
		)
		(fp_rect
			(start -0.508 0.9398)
			(end 0.508 -0.9398)
			(stroke
				(width 0)
				(type default)
			)
			(fill no)
			(layer "F.CrtYd")
		)
		(fp_rect
			(start -0.508 0.9398)
			(end 0.508 -0.9398)
			(stroke
				(width 0)
				(type default)
			)
			(fill no)
			(layer "F.Fab")
		)
		(pad "1" smd custom
			(at 0 -0.4445 90)
			(size 0.1397 0.1397)
			(layers "F.Cu" "F.Mask" "F.Paste")
			(net "P12V_A")
			(options
				(clearance outline)
				(anchor circle)
			)
			(primitives
				(gr_poly
					(pts
						(arc
							(start -0.1778 -0.2794)
							(mid -0.249642 -0.249642)
							(end -0.2794 -0.1778)
						)
						(arc
							(start -0.2794 0.1778)
							(mid -0.249642 0.249642)
							(end -0.1778 0.2794)
						)
						(arc
							(start 0.1778 0.2794)
							(mid 0.249642 0.249642)
							(end 0.2794 0.1778)
						)
						(arc
							(start 0.2794 -0.1778)
							(mid 0.249642 -0.249642)
							(end 0.1778 -0.2794)
						)
					)
					(width 0)
					(fill yes)
				)
			)
		)
		(pad "2" smd custom
			(at 0 0.4445 90)
			(size 0.1397 0.1397)
			(layers "F.Cu" "F.Mask" "F.Paste")
			(net "SW_HDD_R14")
			(options
				(clearance outline)
				(anchor circle)
			)
			(primitives
				(gr_poly
					(pts
						(arc
							(start -0.1778 -0.2794)
							(mid -0.249642 -0.249642)
							(end -0.2794 -0.1778)
						)
						(arc
							(start -0.2794 0.1778)
							(mid -0.249642 0.249642)
							(end -0.1778 0.2794)
						)
						(arc
							(start 0.1778 0.2794)
							(mid 0.249642 0.249642)
							(end 0.2794 0.1778)
						)
						(arc
							(start 0.2794 -0.1778)
							(mid 0.249642 -0.249642)
							(end 0.1778 -0.2794)
						)
					)
					(width 0)
					(fill yes)
				)
			)
		)
	)
	(footprint ""
		(layer "F.Cu")
		(at 256.970276 -254.97536)
		(property "Reference" "U6"
			(at 0 0 0)
			(layer "F.SilkS")
			(hide yes)
			(effects
				(font
					(size 1.27 1.27)
				)
			)
		)
		(property "Value" "TCA9555PWR-GP"
			(at 0 -6.9342 0)
			(unlocked yes)
			(layer "F.Fab")
			(hide yes)
			(effects
				(font
					(size 1.016 1.016)
					(thickness 0.1524)
				)
			)
		)
		(property "Device Type" "TSOIC24H48"
			(at 0 -8.5852 0)
			(unlocked yes)
			(layer "F.Fab")
			(hide yes)
			(effects
				(font
					(size 1.016 1.016)
					(thickness 0.1524)
				)
			)
		)
		(duplicate_pad_numbers_are_jumpers no)
		(fp_line
			(start -4.2291 -1.397)
			(end 3.81 -1.397)
			(stroke
				(width 0.1524)
				(type default)
			)
			(layer "F.SilkS")
		)
		(fp_line
			(start -4.2291 -0.8001)
			(end -3.429 0)
			(stroke
				(width 0.1524)
				(type default)
			)
			(layer "F.SilkS")
		)
		(fp_line
			(start -4.2291 3.937)
			(end -4.2291 -1.397)
			(stroke
				(width 0.1524)
				(type default)
			)
			(layer "F.SilkS")
		)
		(fp_line
			(start -4.22656 3.81)
			(end -4.2291 1.397)
			(stroke
				(width 0.508)
				(type default)
			)
			(layer "F.SilkS")
		)
		(fp_line
			(start -3.429 0)
			(end -4.2291 0.8001)
			(stroke
				(width 0.1524)
				(type default)
			)
			(layer "F.SilkS")
		)
		(fp_line
			(start 3.81 -1.397)
			(end 3.81 1.397)
			(stroke
				(width 0.1524)
				(type default)
			)
			(layer "F.SilkS")
		)
		(fp_line
			(start 3.81 1.397)
			(end -4.2291 1.397)
			(stroke
				(width 0.1524)
				(type default)
			)
			(layer "F.SilkS")
		)
		(fp_poly
			(pts
				(xy -3.90652 -1.8542) (xy 3.90652 -1.8542) (xy 3.90652 1.8542) (xy -3.90652 1.8542)
			)
			(stroke
				(width 0)
				(type default)
			)
			(fill yes)
			(layer "F.SilkS")
		)
		(fp_poly
			(pts
				(xy -4.2164 3.81) (xy 4.2164 3.81) (xy 4.22656 -3.81) (xy -4.2164 -3.81)
			)
			(stroke
				(width 0)
				(type default)
			)
			(fill no)
			(layer "F.CrtYd")
		)
		(fp_poly
			(pts
				(xy -4.22656 -3.81) (xy 4.22656 -3.81) (xy 4.22656 3.81) (xy -4.22656 3.81)
			)
			(stroke
				(width 0)
				(type default)
			)
			(fill no)
			(layer "F.Fab")
		)
		(pad "1" smd rect
			(at -3.57632 2.8194)
			(size 0.3556 1.524)
			(layers "F.Cu" "F.Mask" "F.Paste")
			(net "IO_EXP6_INT_N")
		)
		(pad "2" smd rect
			(at -2.92608 2.8194)
			(size 0.3556 1.524)
			(layers "F.Cu" "F.Mask" "F.Paste")
			(net "IO_EXP6_A1")
		)
		(pad "3" smd rect
			(at -2.27584 2.8194)
			(size 0.3556 1.524)
			(layers "F.Cu" "F.Mask" "F.Paste")
			(net "IO_EXP6_A2")
		)
		(pad "4" smd rect
			(at -1.6256 2.8194)
			(size 0.3556 1.524)
			(layers "F.Cu" "F.Mask" "F.Paste")
			(net "DRIVE_A_32_INS")
		)
		(pad "5" smd rect
			(at -0.97536 2.8194)
			(size 0.3556 1.524)
			(layers "F.Cu" "F.Mask" "F.Paste")
			(net "DRIVE_A_33_INS")
		)
		(pad "6" smd rect
			(at -0.32512 2.8194)
			(size 0.3556 1.524)
			(layers "F.Cu" "F.Mask" "F.Paste")
			(net "DRIVE_A_34_INS")
		)
		(pad "7" smd rect
			(at 0.32512 2.8194)
			(size 0.3556 1.524)
			(layers "F.Cu" "F.Mask" "F.Paste")
			(net "DRIVE_A_35_INS")
		)
		(pad "8" smd rect
			(at 0.97536 2.8194)
			(size 0.3556 1.524)
			(layers "F.Cu" "F.Mask" "F.Paste")
			(net "Net_332")
		)
		(pad "9" smd rect
			(at 1.6256 2.8194)
			(size 0.3556 1.524)
			(layers "F.Cu" "F.Mask" "F.Paste")
			(net "Net_331")
		)
		(pad "10" smd rect
			(at 2.27584 2.8194)
			(size 0.3556 1.524)
			(layers "F.Cu" "F.Mask" "F.Paste")
			(net "Net_330")
		)
		(pad "11" smd rect
			(at 2.92608 2.8194)
			(size 0.3556 1.524)
			(layers "F.Cu" "F.Mask" "F.Paste")
			(net "Net_329")
		)
		(pad "12" smd rect
			(at 3.57632 2.8194)
			(size 0.3556 1.524)
			(layers "F.Cu" "F.Mask" "F.Paste")
			(net "GND")
		)
		(pad "13" smd rect
			(at 3.57632 -2.8194)
			(size 0.3556 1.524)
			(layers "F.Cu" "F.Mask" "F.Paste")
			(net "DRAWER_CLOSED_N")
		)
		(pad "14" smd rect
			(at 2.92608 -2.8194)
			(size 0.3556 1.524)
			(layers "F.Cu" "F.Mask" "F.Paste")
			(net "FAN_0_INS_N")
		)
		(pad "15" smd rect
			(at 2.27584 -2.8194)
			(size 0.3556 1.524)
			(layers "F.Cu" "F.Mask" "F.Paste")
			(net "FAN_1_INS_N")
		)
		(pad "16" smd rect
			(at 1.6256 -2.8194)
			(size 0.3556 1.524)
			(layers "F.Cu" "F.Mask" "F.Paste")
			(net "FAN_2_INS_N")
		)
		(pad "17" smd rect
			(at 0.97536 -2.8194)
			(size 0.3556 1.524)
			(layers "F.Cu" "F.Mask" "F.Paste")
			(net "FAN_3_INS_N")
		)
		(pad "18" smd rect
			(at 0.32512 -2.8194)
			(size 0.3556 1.524)
			(layers "F.Cu" "F.Mask" "F.Paste")
			(net "IOM_A_INS_N")
		)
		(pad "19" smd rect
			(at -0.32512 -2.8194)
			(size 0.3556 1.524)
			(layers "F.Cu" "F.Mask" "F.Paste")
			(net "IOM_B_INS_N")
		)
		(pad "20" smd rect
			(at -0.97536 -2.8194)
			(size 0.3556 1.524)
			(layers "F.Cu" "F.Mask" "F.Paste")
			(net "SCC_B_INS_N")
		)
		(pad "21" smd rect
			(at -1.6256 -2.8194)
			(size 0.3556 1.524)
			(layers "F.Cu" "F.Mask" "F.Paste")
			(net "IO_EXP6_A0")
		)
		(pad "22" smd rect
			(at -2.27584 -2.8194)
			(size 0.3556 1.524)
			(layers "F.Cu" "F.Mask" "F.Paste")
			(net "IO_EXP6_SCL")
		)
		(pad "23" smd rect
			(at -2.92608 -2.8194)
			(size 0.3556 1.524)
			(layers "F.Cu" "F.Mask" "F.Paste")
			(net "IO_EXP6_SDA")
		)
		(pad "24" smd rect
			(at -3.57632 -2.8194)
			(size 0.3556 1.524)
			(layers "F.Cu" "F.Mask" "F.Paste")
			(net "P3V3_STBY_A")
		)
	)
)
